# TIMECARD (Time Appliance Project (Time Card)) — schematic netlist excerpt (pin names and nets, part order shuffled) for the footprints in the layout excerpt that follows; sources: Cadence DE-HDL packaged netlist, KiCad conversion of R4006-B0001-02_R01.brd

C126  CAPACITOR  0.1UF 10V 10%  pkg SMC_0402R_H022  page 14 : \1\ = XP3R3V_FPGA ; \2\ = SG
C241  CAPACITOR  22UF 10V 20%  pkg SMC_0805R_H057  page 31 : \1\ = XP3R3V_FPGA ; \2\ = SG

(kicad_pcb
	(version 20260206)
	(generator "pcbnew")
	(generator_version "10.0")
	(general
		(thickness 1.6)
		(legacy_teardrops no)
	)
	(paper "A4")
	(title_block
		(title "timecard-production-celestica-r4006 — R4006-B0001-02_R01.brd")
		(comment 1 "Time Appliance Project (Time Card) / footprints 934-935 of 1113")
	)
	(layers
		(0 "F.Cu" signal "TOP")
		(4 "In1.Cu" signal "L02_GND1")
		(6 "In2.Cu" signal "L03_SIG1")
		(8 "In3.Cu" signal "L04_GND2")
		(10 "In4.Cu" signal "L05_VCC1")
		(12 "In5.Cu" signal "L06_VCC2")
		(14 "In6.Cu" signal "L07_GND3")
		(16 "In7.Cu" signal "L08_SIG2")
		(18 "In8.Cu" signal "L09_GND4")
		(2 "B.Cu" signal "BOTTOM")
		(9 "F.Adhes" user "F.Adhesive")
		(11 "B.Adhes" user "B.Adhesive")
		(13 "F.Paste" user "Package Geometry/Pastemask Top")
		(15 "B.Paste" user "Package Geometry/Pastemask Bottom")
		(5 "F.SilkS" user "Ref Des/Silkscreen Top")
		(7 "B.SilkS" user "Ref Des/Silkscreen Bottom")
		(1 "F.Mask" user "Board Geometry/Soldermask Top")
		(3 "B.Mask" user "Board Geometry/Soldermask Bottom")
		(17 "Dwgs.User" user "User.Drawings")
		(19 "Cmts.User" user "User.Comments")
		(21 "Eco1.User" user "User.Eco1")
		(23 "Eco2.User" user "User.Eco2")
		(25 "Edge.Cuts" user "Board Geometry/Outline")
		(27 "Margin" user)
		(31 "F.CrtYd" user "Package Geometry/Place Bound Top")
		(29 "B.CrtYd" user "Package Geometry/Place Bound Bottom")
		(35 "F.Fab" user "Ref Des/Assembly Top")
		(33 "B.Fab" user "Ref Des/Assembly Bottom")
	)
	(footprint ""
		(layer "B.Cu")
		(at 113.846864 -49.32299 -90)
		(property "Reference" "C126"
			(at -1.85801 -0.929386 270)
			(unlocked yes)
			(layer "B.SilkS")
			(effects
				(font
					(size 0.635 0.4064)
					(thickness 0.1524)
				)
				(justify mirror)
			)
		)
		(property "Value" "VAL*"
			(at 0 3.718306 270)
			(unlocked yes)
			(layer "B.Fab")
			(hide yes)
			(effects
				(font
					(size 0.7874 0.5842)
					(thickness 0.127)
				)
				(justify mirror)
			)
		)
		(property "Tolerance" "TOL*"
			(at 0 4.861306 270)
			(unlocked yes)
			(layer "Cmts.User")
			(hide yes)
			(effects
				(font
					(size 0.7874 0.5842)
					(thickness 0.127)
				)
				(justify mirror)
			)
		)
		(property "User Part Number" "PARTNUM*"
			(at 0 2.575306 270)
			(unlocked yes)
			(layer "Cmts.User")
			(hide yes)
			(effects
				(font
					(size 0.7874 0.5842)
					(thickness 0.127)
				)
				(justify mirror)
			)
		)
		(property "Device Type" "CAPACITOR-G105-0B104-CK,0.1UF,A"
			(at 0 1.432306 270)
			(unlocked yes)
			(layer "B.Fab")
			(hide yes)
			(effects
				(font
					(size 0.7874 0.5842)
					(thickness 0.127)
				)
				(justify mirror)
			)
		)
		(duplicate_pad_numbers_are_jumpers no)
		(fp_line
			(start -0.970026 0.4699)
			(end 0.970026 0.4699)
			(stroke
				(width 0.1)
				(type default)
			)
			(layer "B.SilkS")
		)
		(fp_line
			(start 0.970026 0.4699)
			(end 0.970026 -0.4699)
			(stroke
				(width 0.1)
				(type default)
			)
			(layer "B.SilkS")
		)
		(fp_line
			(start -0.970026 -0.4699)
			(end -0.970026 0.4699)
			(stroke
				(width 0.1)
				(type default)
			)
			(layer "B.SilkS")
		)
		(fp_line
			(start 0.970026 -0.4699)
			(end -0.970026 -0.4699)
			(stroke
				(width 0.1)
				(type default)
			)
			(layer "B.SilkS")
		)
		(fp_poly
			(pts
				(xy 0.970026 0.4699) (xy -0.970026 0.4699) (xy -0.970026 -0.4699) (xy 0.970026 -0.4699)
			)
			(stroke
				(width 0)
				(type default)
			)
			(fill no)
			(layer "B.CrtYd")
		)
		(fp_line
			(start -0.508 0.3048)
			(end 0.508 0.3048)
			(stroke
				(width 0.1)
				(type default)
			)
			(layer "B.Fab")
		)
		(fp_line
			(start 0.508 0.3048)
			(end 0.508 -0.3048)
			(stroke
				(width 0.1)
				(type default)
			)
			(layer "B.Fab")
		)
		(fp_line
			(start -0.508 -0.3048)
			(end -0.508 0.3048)
			(stroke
				(width 0.1)
				(type default)
			)
			(layer "B.Fab")
		)
		(fp_line
			(start 0.508 -0.3048)
			(end -0.508 -0.3048)
			(stroke
				(width 0.1)
				(type default)
			)
			(layer "B.Fab")
		)
		(pad "1" smd circle
			(at 0.500126 0 90)
			(size 0.635 0.635)
			(layers "B.Cu" "B.Mask" "B.Paste")
			(net "XP3R3V_FPGA")
		)
		(pad "2" smd circle
			(at -0.500126 0 90)
			(size 0.635 0.635)
			(layers "B.Cu" "B.Mask" "B.Paste")
			(net "SG")
		)
	)
	(footprint ""
		(layer "B.Cu")
		(at 105.8418 -74.5744)
		(property "Reference" "C241"
			(at -3.81 -0.08763 0)
			(unlocked yes)
			(layer "B.SilkS")
			(effects
				(font
					(size 0.7874 0.5842)
					(thickness 0.1524)
				)
				(justify mirror)
			)
		)
		(property "Value" "VAL*"
			(at -0.0762 3.134106 0)
			(unlocked yes)
			(layer "B.Fab")
			(hide yes)
			(effects
				(font
					(size 0.7874 0.5842)
					(thickness 0.1524)
				)
				(justify mirror)
			)
		)
		(property "Device Type" "CAPACITOR-G107-0F226-CM,22UF,2A"
			(at -0.0508 2.194306 0)
			(unlocked yes)
			(layer "B.Fab")
			(hide yes)
			(effects
				(font
					(size 0.7874 0.5842)
					(thickness 0.1524)
				)
				(justify mirror)
			)
		)
		(property "User Part Number" "PARTNUM*"
			(at -0.1016 5.013706 0)
			(unlocked yes)
			(layer "Cmts.User")
			(hide yes)
			(effects
				(font
					(size 0.7874 0.5842)
					(thickness 0.1524)
				)
				(justify mirror)
			)
		)
		(property "Tolerance" "TOL*"
			(at -0.0762 4.048506 0)
			(unlocked yes)
			(layer "Cmts.User")
			(hide yes)
			(effects
				(font
					(size 0.7874 0.5842)
					(thickness 0.1524)
				)
				(justify mirror)
			)
		)
		(duplicate_pad_numbers_are_jumpers no)
		(fp_line
			(start -1.5748 -0.9398)
			(end 1.5748 -0.9398)
			(stroke
				(width 0.1)
				(type default)
			)
			(layer "B.SilkS")
		)
		(fp_line
			(start -1.5748 0.9398)
			(end -1.5748 -0.9398)
			(stroke
				(width 0.1)
				(type default)
			)
			(layer "B.SilkS")
		)
		(fp_line
			(start 1.5748 -0.9398)
			(end 1.5748 0.9398)
			(stroke
				(width 0.1)
				(type default)
			)
			(layer "B.SilkS")
		)
		(fp_line
			(start 1.5748 0.9398)
			(end -1.5748 0.9398)
			(stroke
				(width 0.1)
				(type default)
			)
			(layer "B.SilkS")
		)
		(fp_rect
			(start 1.5748 -0.9398)
			(end -1.5748 0.9398)
			(stroke
				(width 0)
				(type default)
			)
			(fill no)
			(layer "B.CrtYd")
		)
		(fp_line
			(start -1.016 -0.635)
			(end 1.016 -0.635)
			(stroke
				(width 0.1)
				(type default)
			)
			(layer "B.Fab")
		)
		(fp_line
			(start -1.016 0.635)
			(end -1.016 -0.635)
			(stroke
				(width 0.1)
				(type default)
			)
			(layer "B.Fab")
		)
		(fp_line
			(start 1.016 -0.635)
			(end 1.016 0.635)
			(stroke
				(width 0.1)
				(type default)
			)
			(layer "B.Fab")
		)
		(fp_line
			(start 1.016 0.635)
			(end -1.016 0.635)
			(stroke
				(width 0.1)
				(type default)
			)
			(layer "B.Fab")
		)
		(pad "1" smd rect
			(at 0.8382 0 180)
			(size 0.9652 1.3716)
			(layers "B.Cu" "B.Mask" "B.Paste")
			(net "XP3R3V_FPGA")
		)
		(pad "2" smd rect
			(at -0.8382 0 180)
			(size 0.9652 1.3716)
			(layers "B.Cu" "B.Mask" "B.Paste")
			(net "SG")
		)
		(zone
			(layer "B.Cu")
			(hatch none 0.5)
			(connect_pads
				(clearance 0)
			)
			(min_thickness 0.25)
			(keepout
				(tracks allowed)
				(vias not_allowed)
				(pads allowed)
				(copperpour not_allowed)
				(footprints allowed)
			)
			(placement
				(enabled no)
				(sheetname "")
			)
			(fill
				(thermal_gap 0.5)
				(thermal_bridge_width 0.5)
				(island_removal_mode 0)
			)
			(polygon
				(pts
					(xy 106.0704 -75.2094) (xy 105.6132 -75.2094) (xy 105.6132 -73.9394) (xy 106.0704 -73.9394)
				)
			)
		)
	)
)
